# TIMECARD (Time Appliance Project (Time Card)) — schematic netlist excerpt (pin names and nets, part order shuffled) for the footprints in the layout excerpt that follows; sources: Cadence DE-HDL packaged netlist, KiCad conversion of R4006-B0001-02_R01.brd

C298  CAPACITOR  0.1UF 25V 10% X7R  pkg SMC_0402R_H022  page 33 : \1\ = UNNAMED_525_CAPACITOR_I7_1 ; \2\ = SG
R290  RESISTOR  4.7KOHM 1%  pkg SMC_0402R_H016  page 20 : \1\ = XP3R3V_FPGA ; \2\ = BNO080_SA0

(kicad_pcb
	(version 20260206)
	(generator "pcbnew")
	(generator_version "10.0")
	(general
		(thickness 1.6)
		(legacy_teardrops no)
	)
	(paper "A4")
	(title_block
		(title "timecard-production-celestica-r4006 — R4006-B0001-02_R01.brd")
		(comment 1 "Time Appliance Project (Time Card) / footprints 155-156 of 1113")
	)
	(layers
		(0 "F.Cu" signal "TOP")
		(4 "In1.Cu" signal "L02_GND1")
		(6 "In2.Cu" signal "L03_SIG1")
		(8 "In3.Cu" signal "L04_GND2")
		(10 "In4.Cu" signal "L05_VCC1")
		(12 "In5.Cu" signal "L06_VCC2")
		(14 "In6.Cu" signal "L07_GND3")
		(16 "In7.Cu" signal "L08_SIG2")
		(18 "In8.Cu" signal "L09_GND4")
		(2 "B.Cu" signal "BOTTOM")
		(9 "F.Adhes" user "F.Adhesive")
		(11 "B.Adhes" user "B.Adhesive")
		(13 "F.Paste" user "Package Geometry/Pastemask Top")
		(15 "B.Paste" user "Package Geometry/Pastemask Bottom")
		(5 "F.SilkS" user "Ref Des/Silkscreen Top")
		(7 "B.SilkS" user "Ref Des/Silkscreen Bottom")
		(1 "F.Mask" user "Board Geometry/Soldermask Top")
		(3 "B.Mask" user "Board Geometry/Soldermask Bottom")
		(17 "Dwgs.User" user "User.Drawings")
		(19 "Cmts.User" user "User.Comments")
		(21 "Eco1.User" user "User.Eco1")
		(23 "Eco2.User" user "User.Eco2")
		(25 "Edge.Cuts" user "Board Geometry/Outline")
		(27 "Margin" user)
		(31 "F.CrtYd" user "Package Geometry/Place Bound Top")
		(29 "B.CrtYd" user "Package Geometry/Place Bound Bottom")
		(35 "F.Fab" user "Ref Des/Assembly Top")
		(33 "B.Fab" user "Ref Des/Assembly Bottom")
	)
	(footprint ""
		(layer "F.Cu")
		(at 83.185 -54.991)
		(property "Reference" "R290"
			(at -9.398 -18.62963 0)
			(unlocked yes)
			(layer "F.SilkS")
			(effects
				(font
					(size 0.7874 0.5842)
					(thickness 0.1524)
				)
			)
		)
		(property "Value" "VAL*"
			(at 0.02032 2.13233 0)
			(unlocked yes)
			(layer "F.Fab")
			(hide yes)
			(effects
				(font
					(size 0.7874 0.5842)
					(thickness 0.1524)
				)
			)
		)
		(property "Tolerance" "TOL*"
			(at 0.044704 3.05435 0)
			(unlocked yes)
			(layer "Cmts.User")
			(hide yes)
			(effects
				(font
					(size 0.7874 0.5842)
					(thickness 0.1524)
				)
			)
		)
		(property "User Part Number" "PARTNUM*"
			(at 0.02032 4.024884 0)
			(unlocked yes)
			(layer "Cmts.User")
			(hide yes)
			(effects
				(font
					(size 0.7874 0.5842)
					(thickness 0.1524)
				)
			)
		)
		(property "Device Type" "RESISTOR-G155-14701-01,4.7KOHMA"
			(at 0.008382 1.210564 0)
			(unlocked yes)
			(layer "F.Fab")
			(hide yes)
			(effects
				(font
					(size 0.7874 0.5842)
					(thickness 0.1524)
				)
			)
		)
		(duplicate_pad_numbers_are_jumpers no)
		(fp_line
			(start -1.143 -0.5588)
			(end -1.143 0.5588)
			(stroke
				(width 0.1)
				(type default)
			)
			(layer "F.SilkS")
		)
		(fp_line
			(start -1.143 0.5588)
			(end 1.143 0.5588)
			(stroke
				(width 0.1)
				(type default)
			)
			(layer "F.SilkS")
		)
		(fp_line
			(start 1.143 -0.5588)
			(end -1.143 -0.5588)
			(stroke
				(width 0.1)
				(type default)
			)
			(layer "F.SilkS")
		)
		(fp_line
			(start 1.143 0.5588)
			(end 1.143 -0.5588)
			(stroke
				(width 0.1)
				(type default)
			)
			(layer "F.SilkS")
		)
		(fp_rect
			(start -1.143 -0.5588)
			(end 1.143 0.5588)
			(stroke
				(width 0)
				(type default)
			)
			(fill no)
			(layer "F.CrtYd")
		)
		(fp_line
			(start -0.508 -0.3048)
			(end -0.508 0.3048)
			(stroke
				(width 0.1)
				(type default)
			)
			(layer "F.Fab")
		)
		(fp_line
			(start -0.508 0.3048)
			(end 0.508 0.3048)
			(stroke
				(width 0.1)
				(type default)
			)
			(layer "F.Fab")
		)
		(fp_line
			(start 0.508 -0.3048)
			(end -0.508 -0.3048)
			(stroke
				(width 0.1)
				(type default)
			)
			(layer "F.Fab")
		)
		(fp_line
			(start 0.508 0.3048)
			(end 0.508 -0.3048)
			(stroke
				(width 0.1)
				(type default)
			)
			(layer "F.Fab")
		)
		(pad "1" smd rect
			(at -0.5334 0)
			(size 0.7112 0.6096)
			(layers "F.Cu" "F.Mask" "F.Paste")
			(net "XP3R3V_FPGA")
		)
		(pad "2" smd rect
			(at 0.5334 0)
			(size 0.7112 0.6096)
			(layers "F.Cu" "F.Mask" "F.Paste")
			(net "BNO080_SA0")
		)
		(zone
			(layer "F.Cu")
			(hatch none 0.5)
			(connect_pads
				(clearance 0)
			)
			(min_thickness 0.25)
			(keepout
				(tracks allowed)
				(vias not_allowed)
				(pads allowed)
				(copperpour not_allowed)
				(footprints allowed)
			)
			(placement
				(enabled no)
				(sheetname "")
			)
			(fill
				(thermal_gap 0.5)
				(thermal_bridge_width 0.5)
				(island_removal_mode 0)
			)
			(polygon
				(pts
					(xy 83.1088 -55.2958) (xy 83.1088 -54.6862) (xy 83.2612 -54.6862) (xy 83.2612 -55.2958)
				)
			)
		)
	)
	(footprint ""
		(layer "F.Cu")
		(at 46.736 -81.026)
		(property "Reference" "C298"
			(at 3.81 0.16637 0)
			(unlocked yes)
			(layer "F.SilkS")
			(effects
				(font
					(size 0.7874 0.5842)
					(thickness 0.1524)
				)
			)
		)
		(property "Value" "VAL*"
			(at 0.0762 2.067306 0)
			(unlocked yes)
			(layer "F.Fab")
			(hide yes)
			(effects
				(font
					(size 0.7874 0.5842)
					(thickness 0.1524)
				)
			)
		)
		(property "Tolerance" "TOL*"
			(at 0.0762 3.032506 0)
			(unlocked yes)
			(layer "Cmts.User")
			(hide yes)
			(effects
				(font
					(size 0.7874 0.5842)
					(thickness 0.1524)
				)
			)
		)
		(property "User Part Number" "PARTNUM*"
			(at 0.1016 4.023106 0)
			(unlocked yes)
			(layer "Cmts.User")
			(hide yes)
			(effects
				(font
					(size 0.7874 0.5842)
					(thickness 0.1524)
				)
			)
		)
		(property "Device Type" "CAPACITOR-G105-0B104-EK,0.1UF,A"
			(at 0.0508 1.127506 0)
			(unlocked yes)
			(layer "F.Fab")
			(hide yes)
			(effects
				(font
					(size 0.7874 0.5842)
					(thickness 0.1524)
				)
			)
		)
		(duplicate_pad_numbers_are_jumpers no)
		(fp_line
			(start -1.143 -0.5588)
			(end -1.143 0.5588)
			(stroke
				(width 0.1)
				(type default)
			)
			(layer "F.SilkS")
		)
		(fp_line
			(start -1.143 0.5588)
			(end 1.143 0.5588)
			(stroke
				(width 0.1)
				(type default)
			)
			(layer "F.SilkS")
		)
		(fp_line
			(start 1.143 -0.5588)
			(end -1.143 -0.5588)
			(stroke
				(width 0.1)
				(type default)
			)
			(layer "F.SilkS")
		)
		(fp_line
			(start 1.143 0.5588)
			(end 1.143 -0.5588)
			(stroke
				(width 0.1)
				(type default)
			)
			(layer "F.SilkS")
		)
		(fp_poly
			(pts
				(xy -1.143 0.5588) (xy 1.143 0.5588) (xy 1.143 -0.5588) (xy -1.143 -0.5588)
			)
			(stroke
				(width 0)
				(type default)
			)
			(fill no)
			(layer "F.CrtYd")
		)
		(fp_line
			(start -0.508 -0.3048)
			(end -0.508 0.3048)
			(stroke
				(width 0.1)
				(type default)
			)
			(layer "F.Fab")
		)
		(fp_line
			(start -0.508 0.3048)
			(end 0.508 0.3048)
			(stroke
				(width 0.1)
				(type default)
			)
			(layer "F.Fab")
		)
		(fp_line
			(start 0.508 -0.3048)
			(end -0.508 -0.3048)
			(stroke
				(width 0.1)
				(type default)
			)
			(layer "F.Fab")
		)
		(fp_line
			(start 0.508 0.3048)
			(end 0.508 -0.3048)
			(stroke
				(width 0.1)
				(type default)
			)
			(layer "F.Fab")
		)
		(pad "1" smd rect
			(at -0.5334 0)
			(size 0.7112 0.6096)
			(layers "F.Cu" "F.Mask" "F.Paste")
			(net "UNNAMED_525_CAPACITOR_I7_1")
		)
		(pad "2" smd rect
			(at 0.5334 0)
			(size 0.7112 0.6096)
			(layers "F.Cu" "F.Mask" "F.Paste")
			(net "SG")
		)
		(zone
			(layer "F.Cu")
			(hatch none 0.5)
			(connect_pads
				(clearance 0)
			)
			(min_thickness 0.25)
			(keepout
				(tracks allowed)
				(vias not_allowed)
				(pads allowed)
				(copperpour not_allowed)
				(footprints allowed)
			)
			(placement
				(enabled no)
				(sheetname "")
			)
			(fill
				(thermal_gap 0.5)
				(thermal_bridge_width 0.5)
				(island_removal_mode 0)
			)
			(polygon
				(pts
					(xy 46.6598 -80.7212) (xy 46.8122 -80.7212) (xy 46.8122 -81.3308) (xy 46.6598 -81.3308)
				)
			)
		)
		(zone
			(layer "F.Cu")
			(hatch none 0.5)
			(connect_pads
				(clearance 0)
			)
			(min_thickness 0.25)
			(keepout
				(tracks not_allowed)
				(vias allowed)
				(pads allowed)
				(copperpour not_allowed)
				(footprints allowed)
			)
			(placement
				(enabled no)
				(sheetname "")
			)
			(fill
				(thermal_gap 0.5)
				(thermal_bridge_width 0.5)
				(island_removal_mode 0)
			)
			(polygon
				(pts
					(xy 46.6598 -80.7212) (xy 46.8122 -80.7212) (xy 46.8122 -81.3308) (xy 46.6598 -81.3308)
				)
			)
		)
	)
)
